# SCM (Grand Teton) — schematic netlist excerpt (pin names and nets, part order shuffled) for the footprints in the layout excerpt that follows; sources: Cadence DE-HDL packaged netlist, KiCad conversion of 12092022_DA0F0TMDCD0_F0T_Management_Board_D_brd_V3_OCP.brd

R582  Q_RES  33.2 1% CHIP  pkg 0402LF  page 12 : A = SMB_BMC_MM9_R_SDA ; B = SMB_BMC_MM9_SDA
C199  Q_CAP  1UF 25V 10% X6S  pkg C0402  page 50 : A = REAR_ID_RST_BTN_N ; B = GND

(kicad_pcb
	(version 20260206)
	(generator "pcbnew")
	(generator_version "10.0")
	(general
		(thickness 1.6)
		(legacy_teardrops no)
	)
	(paper "A4")
	(title_block
		(title "12092022_DA0F0TMDCD0_F0T_Management_Board_D_brd_V3_OCP.brd")
		(comment 1 "Grand Teton / footprints 647-648 of 1440")
	)
	(layers
		(0 "F.Cu" signal "TOP")
		(4 "In1.Cu" signal "GND")
		(6 "In2.Cu" signal "IN1")
		(8 "In3.Cu" signal "GND1")
		(10 "In4.Cu" signal "IN2")
		(12 "In5.Cu" signal "VCC")
		(14 "In6.Cu" signal "VCC1")
		(16 "In7.Cu" signal "IN3")
		(18 "In8.Cu" signal "GND2")
		(20 "In9.Cu" signal "IN4")
		(22 "In10.Cu" signal "GND3")
		(2 "B.Cu" signal "BOTTOM")
		(9 "F.Adhes" user "F.Adhesive")
		(11 "B.Adhes" user "B.Adhesive")
		(13 "F.Paste" user "Package Geometry/Pastemask Top")
		(15 "B.Paste" user "Package Geometry/Pastemask Bottom")
		(5 "F.SilkS" user "Ref Des/Silkscreen Top")
		(7 "B.SilkS" user "Ref Des/Silkscreen Bottom")
		(1 "F.Mask" user "Board Geometry/Soldermask Top")
		(3 "B.Mask" user "Board Geometry/Soldermask Bottom")
		(17 "Dwgs.User" user "User.Drawings")
		(19 "Cmts.User" user "User.Comments")
		(21 "Eco1.User" user "User.Eco1")
		(23 "Eco2.User" user "User.Eco2")
		(25 "Edge.Cuts" user "Board Geometry/Outline")
		(27 "Margin" user)
		(31 "F.CrtYd" user "Package Geometry/Place Bound Top")
		(29 "B.CrtYd" user "Package Geometry/Place Bound Bottom")
		(35 "F.Fab" user "Ref Des/Assembly Top")
		(33 "B.Fab" user "Ref Des/Assembly Bottom")
	)
	(footprint ""
		(layer "F.Cu")
		(at 85.2932 -18.796)
		(property "Reference" "C199"
			(at 0 0 0)
			(layer "F.SilkS")
			(hide yes)
			(effects
				(font
					(size 1.27 1.27)
				)
			)
		)
		(property "Value" ""
			(at 0 0 0)
			(layer "F.Fab")
			(effects
				(font
					(size 1.27 1.27)
				)
			)
		)
		(duplicate_pad_numbers_are_jumpers no)
		(fp_line
			(start -0.7874 -0.4064)
			(end 0.7874 -0.4064)
			(stroke
				(width 0.1524)
				(type default)
			)
			(layer "F.SilkS")
		)
		(fp_line
			(start -0.7874 0.4064)
			(end -0.7874 -0.4064)
			(stroke
				(width 0.1524)
				(type default)
			)
			(layer "F.SilkS")
		)
		(fp_line
			(start 0.7874 -0.4064)
			(end 0.7874 0.4064)
			(stroke
				(width 0.1524)
				(type default)
			)
			(layer "F.SilkS")
		)
		(fp_line
			(start 0.7874 0.4064)
			(end -0.7874 0.4064)
			(stroke
				(width 0.1524)
				(type default)
			)
			(layer "F.SilkS")
		)
		(fp_line
			(start -0.67945 -0.305054)
			(end -0.12065 -0.305054)
			(stroke
				(width 0.1)
				(type default)
			)
			(layer "F.Fab")
		)
		(fp_line
			(start -0.67945 0.3048)
			(end -0.67945 -0.305054)
			(stroke
				(width 0.1)
				(type default)
			)
			(layer "F.Fab")
		)
		(fp_line
			(start -0.12065 -0.305054)
			(end -0.12065 -0.2794)
			(stroke
				(width 0.1)
				(type default)
			)
			(layer "F.Fab")
		)
		(fp_line
			(start -0.12065 -0.2794)
			(end 0.12065 -0.2794)
			(stroke
				(width 0.1)
				(type default)
			)
			(layer "F.Fab")
		)
		(fp_line
			(start -0.12065 0.2794)
			(end -0.12065 0.3048)
			(stroke
				(width 0.1)
				(type default)
			)
			(layer "F.Fab")
		)
		(fp_line
			(start -0.12065 0.3048)
			(end -0.67945 0.3048)
			(stroke
				(width 0.1)
				(type default)
			)
			(layer "F.Fab")
		)
		(fp_line
			(start 0.120396 0.2794)
			(end -0.12065 0.2794)
			(stroke
				(width 0.1)
				(type default)
			)
			(layer "F.Fab")
		)
		(fp_line
			(start 0.120396 0.3048)
			(end 0.120396 0.2794)
			(stroke
				(width 0.1)
				(type default)
			)
			(layer "F.Fab")
		)
		(fp_line
			(start 0.12065 -0.3048)
			(end 0.67945 -0.3048)
			(stroke
				(width 0.1)
				(type default)
			)
			(layer "F.Fab")
		)
		(fp_line
			(start 0.12065 -0.2794)
			(end 0.12065 -0.3048)
			(stroke
				(width 0.1)
				(type default)
			)
			(layer "F.Fab")
		)
		(fp_line
			(start 0.67945 -0.3048)
			(end 0.67945 0.3048)
			(stroke
				(width 0.1)
				(type default)
			)
			(layer "F.Fab")
		)
		(fp_line
			(start 0.67945 0.3048)
			(end 0.120396 0.3048)
			(stroke
				(width 0.1)
				(type default)
			)
			(layer "F.Fab")
		)
		(pad "1" smd circle
			(at -0.40005 0)
			(size 0 0)
			(layers "F.Cu" "F.Mask" "F.Paste")
			(net "REAR_ID_RST_BTN_N")
		)
		(pad "2" smd circle
			(at 0.40005 0)
			(size 0 0)
			(layers "F.Cu" "F.Mask" "F.Paste")
			(net "GND")
		)
	)
	(footprint ""
		(layer "F.Cu")
		(at 55.184548 -34.637726 -90)
		(property "Reference" "R582"
			(at 0 0 270)
			(layer "F.SilkS")
			(hide yes)
			(effects
				(font
					(size 1.27 1.27)
				)
			)
		)
		(property "Value" ""
			(at 0 0 270)
			(layer "F.Fab")
			(effects
				(font
					(size 1.27 1.27)
				)
			)
		)
		(duplicate_pad_numbers_are_jumpers no)
		(fp_line
			(start -0.7874 0.4064)
			(end -0.7874 -0.4064)
			(stroke
				(width 0.1524)
				(type default)
			)
			(layer "F.SilkS")
		)
		(fp_line
			(start 0.7874 0.4064)
			(end -0.7874 0.4064)
			(stroke
				(width 0.1524)
				(type default)
			)
			(layer "F.SilkS")
		)
		(fp_line
			(start -0.7874 -0.4064)
			(end 0.7874 -0.4064)
			(stroke
				(width 0.1524)
				(type default)
			)
			(layer "F.SilkS")
		)
		(fp_line
			(start 0.7874 -0.4064)
			(end 0.7874 0.4064)
			(stroke
				(width 0.1524)
				(type default)
			)
			(layer "F.SilkS")
		)
		(fp_line
			(start -0.67945 0.3048)
			(end -0.67945 -0.305054)
			(stroke
				(width 0.1)
				(type default)
			)
			(layer "F.Fab")
		)
		(fp_line
			(start -0.12065 0.3048)
			(end -0.67945 0.3048)
			(stroke
				(width 0.1)
				(type default)
			)
			(layer "F.Fab")
		)
		(fp_line
			(start 0.120396 0.3048)
			(end 0.120396 0.2794)
			(stroke
				(width 0.1)
				(type default)
			)
			(layer "F.Fab")
		)
		(fp_line
			(start 0.67945 0.3048)
			(end 0.120396 0.3048)
			(stroke
				(width 0.1)
				(type default)
			)
			(layer "F.Fab")
		)
		(fp_line
			(start -0.12065 0.2794)
			(end -0.12065 0.3048)
			(stroke
				(width 0.1)
				(type default)
			)
			(layer "F.Fab")
		)
		(fp_line
			(start 0.120396 0.2794)
			(end -0.12065 0.2794)
			(stroke
				(width 0.1)
				(type default)
			)
			(layer "F.Fab")
		)
		(fp_line
			(start -0.12065 -0.2794)
			(end 0.12065 -0.2794)
			(stroke
				(width 0.1)
				(type default)
			)
			(layer "F.Fab")
		)
		(fp_line
			(start 0.12065 -0.2794)
			(end 0.12065 -0.3048)
			(stroke
				(width 0.1)
				(type default)
			)
			(layer "F.Fab")
		)
		(fp_line
			(start 0.12065 -0.3048)
			(end 0.67945 -0.3048)
			(stroke
				(width 0.1)
				(type default)
			)
			(layer "F.Fab")
		)
		(fp_line
			(start 0.67945 -0.3048)
			(end 0.67945 0.3048)
			(stroke
				(width 0.1)
				(type default)
			)
			(layer "F.Fab")
		)
		(fp_line
			(start -0.67945 -0.305054)
			(end -0.12065 -0.305054)
			(stroke
				(width 0.1)
				(type default)
			)
			(layer "F.Fab")
		)
		(fp_line
			(start -0.12065 -0.305054)
			(end -0.12065 -0.2794)
			(stroke
				(width 0.1)
				(type default)
			)
			(layer "F.Fab")
		)
		(pad "1" smd circle
			(at -0.40005 0 270)
			(size 0 0)
			(layers "F.Cu" "F.Mask" "F.Paste")
			(net "SMB_BMC_MM9_R_SDA")
		)
		(pad "2" smd circle
			(at 0.40005 0 270)
			(size 0 0)
			(layers "F.Cu" "F.Mask" "F.Paste")
			(net "SMB_BMC_MM9_SDA")
		)
	)
)
